# TIMECARD (Time Appliance Project (Time Card)) — schematic netlist excerpt (pin names and nets, part order shuffled) for the footprints in the layout excerpt that follows; sources: Cadence DE-HDL packaged netlist, KiCad conversion of R4006-B0001-02_R01.brd

R313  RESISTOR  0OHM -  pkg SMC_0402R_H016  page 16 : \1\ = RGB_LED_I2C_SCL ; \2\ = EEPROM_SCL
R238  RESISTOR  33OHM 1%  pkg SMC_0402R_H016  page 11 : \1\ = FPGA_D01 ; \2\ = FPGA_FLASH_DQ1_MISO

(kicad_pcb
	(version 20260206)
	(generator "pcbnew")
	(generator_version "10.0")
	(general
		(thickness 1.6)
		(legacy_teardrops no)
	)
	(paper "A4")
	(title_block
		(title "timecard-production-celestica-r4006 — R4006-B0001-02_R01.brd")
		(comment 1 "Time Appliance Project (Time Card) / footprints 14-15 of 1113")
	)
	(layers
		(0 "F.Cu" signal "TOP")
		(4 "In1.Cu" signal "L02_GND1")
		(6 "In2.Cu" signal "L03_SIG1")
		(8 "In3.Cu" signal "L04_GND2")
		(10 "In4.Cu" signal "L05_VCC1")
		(12 "In5.Cu" signal "L06_VCC2")
		(14 "In6.Cu" signal "L07_GND3")
		(16 "In7.Cu" signal "L08_SIG2")
		(18 "In8.Cu" signal "L09_GND4")
		(2 "B.Cu" signal "BOTTOM")
		(9 "F.Adhes" user "F.Adhesive")
		(11 "B.Adhes" user "B.Adhesive")
		(13 "F.Paste" user "Package Geometry/Pastemask Top")
		(15 "B.Paste" user "Package Geometry/Pastemask Bottom")
		(5 "F.SilkS" user "Ref Des/Silkscreen Top")
		(7 "B.SilkS" user "Ref Des/Silkscreen Bottom")
		(1 "F.Mask" user "Board Geometry/Soldermask Top")
		(3 "B.Mask" user "Board Geometry/Soldermask Bottom")
		(17 "Dwgs.User" user "User.Drawings")
		(19 "Cmts.User" user "User.Comments")
		(21 "Eco1.User" user "User.Eco1")
		(23 "Eco2.User" user "User.Eco2")
		(25 "Edge.Cuts" user "Board Geometry/Outline")
		(27 "Margin" user)
		(31 "F.CrtYd" user "Package Geometry/Place Bound Top")
		(29 "B.CrtYd" user "Package Geometry/Place Bound Bottom")
		(35 "F.Fab" user "Ref Des/Assembly Top")
		(33 "B.Fab" user "Ref Des/Assembly Bottom")
	)
	(footprint ""
		(layer "F.Cu")
		(at 115.189 -59.563 90)
		(property "Reference" "R238"
			(at -0.635 -1.86563 90)
			(unlocked yes)
			(layer "F.SilkS")
			(effects
				(font
					(size 0.7874 0.5842)
					(thickness 0.1524)
				)
			)
		)
		(property "Value" "VAL*"
			(at 0.02032 2.13233 90)
			(unlocked yes)
			(layer "F.Fab")
			(hide yes)
			(effects
				(font
					(size 0.7874 0.5842)
					(thickness 0.1524)
				)
			)
		)
		(property "Tolerance" "TOL*"
			(at 0.044704 3.05435 90)
			(unlocked yes)
			(layer "Cmts.User")
			(hide yes)
			(effects
				(font
					(size 0.7874 0.5842)
					(thickness 0.1524)
				)
			)
		)
		(property "User Part Number" "PARTNUM*"
			(at 0.02032 4.024884 90)
			(unlocked yes)
			(layer "Cmts.User")
			(hide yes)
			(effects
				(font
					(size 0.7874 0.5842)
					(thickness 0.1524)
				)
			)
		)
		(property "Device Type" "RESISTOR-G155-133R0-01,33OHM,1%"
			(at 0.008382 1.210564 90)
			(unlocked yes)
			(layer "F.Fab")
			(hide yes)
			(effects
				(font
					(size 0.7874 0.5842)
					(thickness 0.1524)
				)
			)
		)
		(duplicate_pad_numbers_are_jumpers no)
		(fp_line
			(start 1.143 -0.5588)
			(end -1.143 -0.5588)
			(stroke
				(width 0.1)
				(type default)
			)
			(layer "F.SilkS")
		)
		(fp_line
			(start -1.143 -0.5588)
			(end -1.143 0.5588)
			(stroke
				(width 0.1)
				(type default)
			)
			(layer "F.SilkS")
		)
		(fp_line
			(start 1.143 0.5588)
			(end 1.143 -0.5588)
			(stroke
				(width 0.1)
				(type default)
			)
			(layer "F.SilkS")
		)
		(fp_line
			(start -1.143 0.5588)
			(end 1.143 0.5588)
			(stroke
				(width 0.1)
				(type default)
			)
			(layer "F.SilkS")
		)
		(fp_poly
			(pts
				(xy -1.143 0.5588) (xy 1.143 0.5588) (xy 1.143 -0.5588) (xy -1.143 -0.5588)
			)
			(stroke
				(width 0)
				(type default)
			)
			(fill no)
			(layer "F.CrtYd")
		)
		(fp_line
			(start 0.508 -0.3048)
			(end -0.508 -0.3048)
			(stroke
				(width 0.1)
				(type default)
			)
			(layer "F.Fab")
		)
		(fp_line
			(start -0.508 -0.3048)
			(end -0.508 0.3048)
			(stroke
				(width 0.1)
				(type default)
			)
			(layer "F.Fab")
		)
		(fp_line
			(start 0.508 0.3048)
			(end 0.508 -0.3048)
			(stroke
				(width 0.1)
				(type default)
			)
			(layer "F.Fab")
		)
		(fp_line
			(start -0.508 0.3048)
			(end 0.508 0.3048)
			(stroke
				(width 0.1)
				(type default)
			)
			(layer "F.Fab")
		)
		(pad "1" smd rect
			(at -0.5334 0 90)
			(size 0.7112 0.6096)
			(layers "F.Cu" "F.Mask" "F.Paste")
			(net "FPGA_D01")
		)
		(pad "2" smd rect
			(at 0.5334 0 90)
			(size 0.7112 0.6096)
			(layers "F.Cu" "F.Mask" "F.Paste")
			(net "FPGA_FLASH_DQ1_MISO")
		)
		(zone
			(layer "F.Cu")
			(hatch none 0.5)
			(connect_pads
				(clearance 0)
			)
			(min_thickness 0.25)
			(keepout
				(tracks allowed)
				(vias not_allowed)
				(pads allowed)
				(copperpour not_allowed)
				(footprints allowed)
			)
			(placement
				(enabled no)
				(sheetname "")
			)
			(fill
				(thermal_gap 0.5)
				(thermal_bridge_width 0.5)
				(island_removal_mode 0)
			)
			(polygon
				(pts
					(xy 115.4938 -59.4868) (xy 115.4938 -59.6392) (xy 114.8842 -59.6392) (xy 114.8842 -59.4868)
				)
			)
		)
		(zone
			(layer "F.Cu")
			(hatch none 0.5)
			(connect_pads
				(clearance 0)
			)
			(min_thickness 0.25)
			(keepout
				(tracks not_allowed)
				(vias allowed)
				(pads allowed)
				(copperpour not_allowed)
				(footprints allowed)
			)
			(placement
				(enabled no)
				(sheetname "")
			)
			(fill
				(thermal_gap 0.5)
				(thermal_bridge_width 0.5)
				(island_removal_mode 0)
			)
			(polygon
				(pts
					(xy 115.4938 -59.4868) (xy 115.4938 -59.6392) (xy 114.8842 -59.6392) (xy 114.8842 -59.4868)
				)
			)
		)
	)
	(footprint ""
		(layer "F.Cu")
		(at 33.77438 -19.1262 180)
		(property "Reference" "R313"
			(at -3.05562 -0.75057 0)
			(unlocked yes)
			(layer "F.SilkS")
			(effects
				(font
					(size 0.7874 0.5842)
					(thickness 0.1524)
				)
			)
		)
		(property "Value" "VAL*"
			(at 0.02032 2.13233 180)
			(unlocked yes)
			(layer "F.Fab")
			(hide yes)
			(effects
				(font
					(size 0.7874 0.5842)
					(thickness 0.1524)
				)
			)
		)
		(property "Device Type" "RESISTOR-G155-100R0-J0,0OHM,-"
			(at 0.008382 1.210564 180)
			(unlocked yes)
			(layer "F.Fab")
			(hide yes)
			(effects
				(font
					(size 0.7874 0.5842)
					(thickness 0.1524)
				)
			)
		)
		(property "User Part Number" "PARTNUM*"
			(at 0.02032 4.024884 180)
			(unlocked yes)
			(layer "Cmts.User")
			(hide yes)
			(effects
				(font
					(size 0.7874 0.5842)
					(thickness 0.1524)
				)
			)
		)
		(property "Tolerance" "TOL*"
			(at 0.044704 3.05435 180)
			(unlocked yes)
			(layer "Cmts.User")
			(hide yes)
			(effects
				(font
					(size 0.7874 0.5842)
					(thickness 0.1524)
				)
			)
		)
		(duplicate_pad_numbers_are_jumpers no)
		(fp_line
			(start 1.143 0.5588)
			(end 1.143 -0.5588)
			(stroke
				(width 0.1)
				(type default)
			)
			(layer "F.SilkS")
		)
		(fp_line
			(start 1.143 -0.5588)
			(end -1.143 -0.5588)
			(stroke
				(width 0.1)
				(type default)
			)
			(layer "F.SilkS")
		)
		(fp_line
			(start -1.143 0.5588)
			(end 1.143 0.5588)
			(stroke
				(width 0.1)
				(type default)
			)
			(layer "F.SilkS")
		)
		(fp_line
			(start -1.143 -0.5588)
			(end -1.143 0.5588)
			(stroke
				(width 0.1)
				(type default)
			)
			(layer "F.SilkS")
		)
		(fp_poly
			(pts
				(xy -1.143 0.5588) (xy 1.143 0.5588) (xy 1.143 -0.5588) (xy -1.143 -0.5588)
			)
			(stroke
				(width 0)
				(type default)
			)
			(fill no)
			(layer "F.CrtYd")
		)
		(fp_line
			(start 0.508 0.3048)
			(end 0.508 -0.3048)
			(stroke
				(width 0.1)
				(type default)
			)
			(layer "F.Fab")
		)
		(fp_line
			(start 0.508 -0.3048)
			(end -0.508 -0.3048)
			(stroke
				(width 0.1)
				(type default)
			)
			(layer "F.Fab")
		)
		(fp_line
			(start -0.508 0.3048)
			(end 0.508 0.3048)
			(stroke
				(width 0.1)
				(type default)
			)
			(layer "F.Fab")
		)
		(fp_line
			(start -0.508 -0.3048)
			(end -0.508 0.3048)
			(stroke
				(width 0.1)
				(type default)
			)
			(layer "F.Fab")
		)
		(pad "1" smd rect
			(at -0.5334 0 180)
			(size 0.7112 0.6096)
			(layers "F.Cu" "F.Mask" "F.Paste")
			(net "RGB_LED_I2C_SCL")
		)
		(pad "2" smd rect
			(at 0.5334 0 180)
			(size 0.7112 0.6096)
			(layers "F.Cu" "F.Mask" "F.Paste")
			(net "EEPROM_SCL")
		)
		(zone
			(layer "F.Cu")
			(hatch none 0.5)
			(connect_pads
				(clearance 0)
			)
			(min_thickness 0.25)
			(keepout
				(tracks not_allowed)
				(vias allowed)
				(pads allowed)
				(copperpour not_allowed)
				(footprints allowed)
			)
			(placement
				(enabled no)
				(sheetname "")
			)
			(fill
				(thermal_gap 0.5)
				(thermal_bridge_width 0.5)
				(island_removal_mode 0)
			)
			(polygon
				(pts
					(xy 33.85058 -19.431) (xy 33.69818 -19.431) (xy 33.69818 -18.8214) (xy 33.85058 -18.8214)
				)
			)
		)
		(zone
			(layer "F.Cu")
			(hatch none 0.5)
			(connect_pads
				(clearance 0)
			)
			(min_thickness 0.25)
			(keepout
				(tracks allowed)
				(vias not_allowed)
				(pads allowed)
				(copperpour not_allowed)
				(footprints allowed)
			)
			(placement
				(enabled no)
				(sheetname "")
			)
			(fill
				(thermal_gap 0.5)
				(thermal_bridge_width 0.5)
				(island_removal_mode 0)
			)
			(polygon
				(pts
					(xy 33.85058 -19.431) (xy 33.69818 -19.431) (xy 33.69818 -18.8214) (xy 33.85058 -18.8214)
				)
			)
		)
	)
)
